FILE_TYPE = CONNECTIVITY;
{Allegro Design Entry HDL 17.2-2016 S081 (4005846) 1/11/2022}
"PAGE_NUMBER" = 325;
0"NC";
1"AGND_HSC\g";
2"AGND_HSC\g";
3"AGND_HSC\g";
4"AGND_HSC\g";
5"AGND_HSC\g";
6"HSC_VDD\g";
7"P12V_PSU\g";
8"AGND_HSC\g";
9"HSC_VDD\g";
10"P12V_PSU\g";
11"AGND_HSC\g";
12"P12V_AUX\g";
13"AGND_HSC\g";
14"P12V_AUX\g";
15"HSC_VDD_R_4";
16"HSC_ON";
17"HSC_OCREF";
18"HSC_CS_4";
19"HSC_VTEMP";
20"HSC_FAULT";
21"HSC_D_OC_R";
22"HSC_FLT_TYPE";
23"HSC_SCREF";
24"HSC_IMON";
25"HSC_SCREF_4";
26"HSC_MODE_4";
27"HSC_NC1_4";
28"HSC_SS";
29"HSC_SS";
30"HSC_VTEMP";
31"HSC_FAULT";
32"HSC_ON";
33"HSC_OCREF";
34"HSC_CS_3";
35"HSC_IMON";
36"HSC_MODE_3";
37"HSC_VDD_R_3";
38"HSC_SCREF_3";
39"HSC_SCREF";
40"HSC_D_OC_R";
41"HSC_FLT_TYPE";
42"HSC_FLT_TYPE_3";
43"HSC_D_OC_3";
44"HSC_NC1_3";
45"HSC_FLT_TYPE_4";
46"HSC_D_OC_4";
%"UNIVERSAL_GND"
"1","(-1875,-2125)","0","logical_power","I1";
;
HDL_POWER"AGND_HSC"
CDS_LIB"logical_power";
"A"4;
%"Q_CAP"
"1","(-1150,-1825)","0","pure_quanta","I11";
;
PART_NUMBER"CH21006KB16"
VALUE"1NF"
VOLTAGE"50V"
MATERIAL"EMPTY"
PACK_TYPE"0402"
LOCATION"PC2349"
TOLERANCE"10%"
CDS_LIB"pure_quanta"
$SEC"1"
CDS_SEC"1";
"B"
$PN"2"4;
"A"
$PN"1"17;
%"Q_RES"
"2","(-650,-1825)","0","pure_quanta","I12";
;
PART_NUMBER"CS22002BB07"
VALUE"2K"
TOLERANCE"0.1%"
WATTAGE"1/16W"
MATERIAL"CHIP"
PACK_TYPE"0402LF"
ROOM"HSC1_BOM1"
LOCATION"PR3987"
CDS_LIB"pure_quanta"
$SEC"1"
CDS_SEC"1";
"A"
$PN"1"18;
"B"
$PN"2"4;
%"Q_RES"
"2","(-125,-1825)","0","pure_quanta","I13";
;
PART_NUMBER"CS22002BB07"
VALUE"2K"
ROOM"HSC1_BOM1"
PACK_TYPE"0402LF"
MATERIAL"CHIP"
WATTAGE"1/16W"
TOLERANCE"0.1%"
LOCATION"PR3991"
CDS_LIB"pure_quanta"
$SEC"1"
CDS_SEC"1";
"A"
$PN"1"24;
"B"
$PN"2"4;
%"Q_RES"
"1","(-1075,-1000)","0","pure_quanta","I14";
;
PART_NUMBER"CS41202FB05"
VALUE"120K"
MATERIAL"CHIP"
TOLERANCE"1%"
PACK_TYPE"0402LF"
ROOM"HSC1_BOM1"
WATTAGE"1/16W"
LOCATION"PR3984"
CDS_LIB"pure_quanta"
$SEC"1"
CDS_SEC"1";
"B"
$PN"2"26;
"A"
$PN"1"1;
%"Q_RES"
"1","(-475,-1175)","0","pure_quanta","I16";
;
PART_NUMBER"CS00002JB13"
VALUE"0"
MATERIAL"CHIP"
TOLERANCE"5%"
PACK_TYPE"0402LF"
ROOM"HSC1_BOM1"
WATTAGE"1/16W"
LOCATION"PR3989"
CDS_LIB"pure_quanta"
$SEC"1"
CDS_SEC"1";
"B"
$PN"2"25;
"A"
$PN"1"23;
%"MP5991GLUZ"
"1","(850,-1075)","0","pure_quanta","I17";
;
PART_NUMBER"AL005991A00"
PART_TYPE"SMLF"
MATERIAL"IC"
VALUE"MP5991GLU-Z"
ROOM"HSC1_BOM1"
LOCATION"PU297"
NEEDS_NO_SIZE"TRUE"
CDS_LMAN_SYM_OUTLINE"-325,775,325,-775"
CDS_LIB"pure_quanta"
SEC_TYPE""
SEC"1";
"NC1"
$PN"7"27;
"FLT_TYPE"
$PN"6"45;
"SCREF_OCWREF"
$PN"17"25;
"MODE"
$PN"8"26;
"VOUT10"
$PN"32"12;
"VOUT9"
$PN"31"12;
"VOUT8"
$PN"30"12;
"VOUT7"
$PN"29"12;
"VOUT6"
$PN"28"12;
"VOUT5"
$PN"27"12;
"VIN9"
$PN"33"7;
"VIN8"
$PN"16"7;
"VIN7"
$PN"15"7;
"VIN6"
$PN"14"7;
"D_OC"
$PN"3"46;
"VOUT4"
$PN"26"12;
"VOUT3"
$PN"25"12;
"VOUT2"
$PN"2"12;
"VOUT1"
$PN"1"12;
"VTEMP"
$PN"18"19;
"GOK"
$PN"5"20;
"SS"
$PN"19"28;
"GND"
$PN"20"4;
"VDD33"
$PN"21"15;
"IMON"
$PN"22"24;
"CS"
$PN"23"18;
"OCREF"
$PN"24"17;
"ON"
$PN"4"16;
"VIN5"
$PN"13"7;
"VIN4"
$PN"12"7;
"VIN3"
$PN"11"7;
"VIN2"
$PN"10"7;
"VIN1"
$PN"9"7;
%"UNIVERSAL_POWER"
"1","(-125,-200)","0","logical_power","I18";
;
HDL_POWER"P12V_PSU"
ROOM"AUX_SW"
CDS_LIB"logical_power"
BOM_COST"MIO_VRD_SB";
"A"7;
%"Q_CAP"
"1","(-2775,1600)","0","pure_quanta","I19";
;
PART_NUMBER"CH5104KEB02"
VALUE"1UF"
MATERIAL"X6S"
PACK_TYPE"C0402"
VOLTAGE"25V"
ROOM"HSC1_BOM1"
LOCATION"PC3272"
TOLERANCE"10%"
CDS_LIB"pure_quanta"
$SEC"1"
CDS_SEC"1";
"B"
$PN"2"3;
"A"
$PN"1"37;
%"Q_CAP"
"1","(-1875,-1825)","0","pure_quanta","I2";
;
PART_NUMBER"TMP_QCH12206KB14"
VOLTAGE"50V"
PACK_TYPE"0402"
VALUE"220PF"
MATERIAL"EMPTY"
LOCATION"PC2225"
CDS_LIB"pure_quanta"
TOLERANCE"10%"
$SEC"1"
CDS_SEC"1";
"B"
$PN"2"4;
"A"
$PN"1"16;
%"UNIVERSAL_GND"
"1","(-2775,1300)","0","logical_power","I20";
;
HDL_POWER"AGND_HSC"
CDS_LIB"logical_power";
"A"3;
%"Q_RES"
"1","(-2775,2075)","1","pure_quanta","I21";
;
PART_NUMBER"CS00002JB13"
VALUE"0"
TOLERANCE"5%"
MATERIAL"CHIP"
WATTAGE"1/16W"
PACK_TYPE"0402LF"
ROOM"HSC1_BOM1"
LOCATION"PR3980"
CDS_LIB"pure_quanta"
$SEC"1"
CDS_SEC"1";
"B"
$PN"2"9;
"A"
$PN"1"37;
%"UNIVERSAL_GND"
"1","(-1875,650)","0","logical_power","I22";
;
HDL_POWER"AGND_HSC"
CDS_LIB"logical_power";
"A"8;
%"Q_CAP"
"1","(-1875,950)","0","pure_quanta","I23";
;
PART_NUMBER"TMP_QCH12206KB14"
PACK_TYPE"0402"
VOLTAGE"50V"
MATERIAL"EMPTY"
VALUE"220PF"
LOCATION"PC2224"
CDS_LIB"pure_quanta"
TOLERANCE"10%"
$SEC"1"
CDS_SEC"1";
"B"
$PN"2"8;
"A"
$PN"1"32;
%"UNIVERSAL_GND"
"1","(-1900,1700)","0","logical_power","I25";
;
HDL_POWER"AGND_HSC"
CDS_LIB"logical_power";
"A"2;
%"UNIVERSAL_POWER"
"1","(-2775,2325)","0","logical_power","I28";
;
HDL_POWER"HSC_VDD"
ROOM"AUX_SW"
BOM_COST"MIO_VRD_SB"
CDS_LIB"logical_power";
"A"9;
%"Q_CAP"
"1","(-1125,950)","0","pure_quanta","I29";
;
PART_NUMBER"CH21006KB16"
VOLTAGE"50V"
PACK_TYPE"0402"
MATERIAL"EMPTY"
VALUE"1NF"
LOCATION"PC2350"
TOLERANCE"10%"
CDS_LIB"pure_quanta"
$SEC"1"
CDS_SEC"1";
"B"
$PN"2"8;
"A"
$PN"1"33;
%"UNIVERSAL_GND"
"1","(-2750,-1475)","0","logical_power","I3";
;
HDL_POWER"AGND_HSC"
CDS_LIB"logical_power";
"A"5;
%"Q_RES"
"2","(-650,950)","0","pure_quanta","I30";
;
PART_NUMBER"CS22002BB07"
MATERIAL"CHIP"
PACK_TYPE"0402LF"
VALUE"2K"
TOLERANCE"0.1%"
WATTAGE"1/16W"
ROOM"HSC1_BOM1"
LOCATION"PR3986"
CDS_LIB"pure_quanta"
$SEC"1"
CDS_SEC"1";
"A"
$PN"1"34;
"B"
$PN"2"8;
%"Q_RES"
"1","(-1075,1775)","0","pure_quanta","I32";
;
PART_NUMBER"CS41202FB05"
WATTAGE"1/16W"
MATERIAL"CHIP"
TOLERANCE"1%"
VALUE"120K"
PACK_TYPE"0402LF"
ROOM"HSC1_BOM1"
LOCATION"PR3982"
CDS_LIB"pure_quanta"
$SEC"1"
CDS_SEC"1";
"B"
$PN"2"36;
"A"
$PN"1"2;
%"Q_RES"
"1","(-500,1600)","0","pure_quanta","I33";
;
PART_NUMBER"CS00002JB13"
TOLERANCE"5%"
MATERIAL"CHIP"
WATTAGE"1/16W"
VALUE"0"
PACK_TYPE"0402LF"
ROOM"HSC1_BOM1"
LOCATION"PR3988"
CDS_LIB"pure_quanta"
$SEC"1"
CDS_SEC"1";
"B"
$PN"2"38;
"A"
$PN"1"39;
%"Q_RES"
"2","(-125,950)","0","pure_quanta","I34";
;
PART_NUMBER"CS22002BB07"
TOLERANCE"0.1%"
WATTAGE"1/16W"
VALUE"2K"
MATERIAL"CHIP"
PACK_TYPE"0402LF"
ROOM"HSC1_BOM1"
LOCATION"PR3990"
CDS_LIB"pure_quanta"
$SEC"1"
CDS_SEC"1";
"A"
$PN"1"35;
"B"
$PN"2"8;
%"MP5991GLUZ"
"1","(850,1700)","0","pure_quanta","I35";
;
PART_NUMBER"AL005991A00"
PART_TYPE"SMLF"
MATERIAL"IC"
VALUE"MP5991GLU-Z"
ROOM"HSC1_BOM1"
LOCATION"PU296"
CDS_LIB"pure_quanta"
CDS_LMAN_SYM_OUTLINE"-325,775,325,-775"
NEEDS_NO_SIZE"TRUE"
SEC_TYPE""
SEC"1";
"NC1"
$PN"7"44;
"FLT_TYPE"
$PN"6"42;
"SCREF_OCWREF"
$PN"17"38;
"MODE"
$PN"8"36;
"VOUT10"
$PN"32"14;
"VOUT9"
$PN"31"14;
"VOUT8"
$PN"30"14;
"VOUT7"
$PN"29"14;
"VOUT6"
$PN"28"14;
"VOUT5"
$PN"27"14;
"VIN9"
$PN"33"10;
"VIN8"
$PN"16"10;
"VIN7"
$PN"15"10;
"VIN6"
$PN"14"10;
"D_OC"
$PN"3"43;
"VOUT4"
$PN"26"14;
"VOUT3"
$PN"25"14;
"VOUT2"
$PN"2"14;
"VOUT1"
$PN"1"14;
"VTEMP"
$PN"18"30;
"GOK"
$PN"5"31;
"SS"
$PN"19"29;
"GND"
$PN"20"8;
"VDD33"
$PN"21"37;
"IMON"
$PN"22"35;
"CS"
$PN"23"34;
"OCREF"
$PN"24"33;
"ON"
$PN"4"32;
"VIN5"
$PN"13"10;
"VIN4"
$PN"12"10;
"VIN3"
$PN"11"10;
"VIN2"
$PN"10"10;
"VIN1"
$PN"9"10;
%"UNIVERSAL_POWER"
"1","(-125,2575)","0","logical_power","I36";
;
HDL_POWER"P12V_PSU"
ROOM"AUX_SW"
CDS_LIB"logical_power"
BOM_COST"MIO_VRD_SB";
"A"10;
%"UNIVERSAL_GND"
"1","(1825,-2025)","0","logical_power","I37";
;
HDL_POWER"AGND_HSC"
CDS_LIB"logical_power";
"A"11;
%"Q_CAP"
"1","(1825,-1800)","0","pure_quanta","I38";
;
PART_NUMBER"CH3683K1B09"
VOLTAGE"16V"
VALUE"0.068UF"
ROOM"HSC1_BOM1"
PACK_TYPE"0402"
MATERIAL"X7R"
LOCATION"PC2227"
TOLERANCE"10%"
CDS_LIB"pure_quanta"
$SEC"1"
CDS_SEC"1";
"B"
$PN"2"11;
"A"
$PN"1"28;
%"Q_RES"
"1","(2325,-1250)","0","pure_quanta","I39";
;
PART_NUMBER"CS00002JB13"
VALUE"0"
WATTAGE"1/16W"
PACK_TYPE"0402LF"
TOLERANCE"5%"
MATERIAL"CHIP"
ROOM"HSC1_BOM1"
LOCATION"PR3995"
CDS_LIB"pure_quanta"
$SEC"1"
CDS_SEC"1";
"B"
$PN"2"22;
"A"
$PN"1"45;
%"Q_CAP"
"1","(-2750,-1175)","0","pure_quanta","I4";
;
PART_NUMBER"CH5104KEB02"
MATERIAL"X6S"
VOLTAGE"25V"
VALUE"1UF"
PACK_TYPE"C0402"
ROOM"HSC1_BOM1"
LOCATION"PC2223"
TOLERANCE"10%"
CDS_LIB"pure_quanta"
$SEC"1"
CDS_SEC"1";
"B"
$PN"2"5;
"A"
$PN"1"15;
%"Q_RES"
"1","(2325,-1075)","0","pure_quanta","I40";
;
PART_NUMBER"CS00002JB13"
MATERIAL"CHIP"
WATTAGE"1/16W"
PACK_TYPE"0402LF"
ROOM"HSC1_BOM1"
VALUE"0"
TOLERANCE"5%"
LOCATION"PR3994"
CDS_LIB"pure_quanta"
$SEC"1"
CDS_SEC"1";
"B"
$PN"2"21;
"A"
$PN"1"46;
%"UNIVERSAL_POWER"
"1","(1950,-200)","0","logical_power","I41";
;
HDL_POWER"P12V_AUX"
ROOM"AUX_SW"
CDS_LIB"logical_power"
BOM_COST"MIO_VRD_SB";
"A"12;
%"UNIVERSAL_GND"
"1","(1825,750)","0","logical_power","I47";
;
HDL_POWER"AGND_HSC"
CDS_LIB"logical_power";
"A"13;
%"Q_CAP"
"1","(1825,975)","0","pure_quanta","I48";
;
PART_NUMBER"CH3683K1B09"
VOLTAGE"16V"
PACK_TYPE"0402"
MATERIAL"X7R"
VALUE"0.068UF"
ROOM"HSC1_BOM1"
LOCATION"PC2226"
TOLERANCE"10%"
CDS_LIB"pure_quanta"
$SEC"1"
CDS_SEC"1";
"B"
$PN"2"13;
"A"
$PN"1"29;
%"Q_RES"
"1","(2325,1525)","0","pure_quanta","I49";
;
PART_NUMBER"CS00002JB13"
TOLERANCE"5%"
MATERIAL"CHIP"
VALUE"0"
PACK_TYPE"0402LF"
WATTAGE"1/16W"
ROOM"HSC1_BOM1"
LOCATION"PR3993"
CDS_LIB"pure_quanta"
$SEC"1"
CDS_SEC"1";
"B"
$PN"2"41;
"A"
$PN"1"42;
%"Q_RES"
"1","(-2750,-700)","1","pure_quanta","I5";
;
PART_NUMBER"CS00002JB13"
VALUE"0"
PACK_TYPE"0402LF"
WATTAGE"1/16W"
MATERIAL"CHIP"
TOLERANCE"5%"
ROOM"HSC1_BOM1"
LOCATION"PR3981"
CDS_LIB"pure_quanta"
$SEC"1"
CDS_SEC"1";
"B"
$PN"2"6;
"A"
$PN"1"15;
%"Q_RES"
"1","(2325,1700)","0","pure_quanta","I50";
;
PART_NUMBER"CS00002JB13"
VALUE"0"
MATERIAL"CHIP"
TOLERANCE"5%"
WATTAGE"1/16W"
PACK_TYPE"0402LF"
ROOM"HSC1_BOM1"
LOCATION"PR3992"
CDS_LIB"pure_quanta"
$SEC"1"
CDS_SEC"1";
"B"
$PN"2"40;
"A"
$PN"1"43;
%"UNIVERSAL_POWER"
"1","(1950,2575)","0","logical_power","I51";
;
HDL_POWER"P12V_AUX"
ROOM"AUX_SW"
CDS_LIB"logical_power"
BOM_COST"MIO_VRD_SB";
"A"14;
%"UNIVERSAL_POWER"
"1","(-2750,-450)","0","logical_power","I6";
;
HDL_POWER"HSC_VDD"
ROOM"AUX_SW"
CDS_LIB"logical_power"
BOM_COST"MIO_VRD_SB";
"A"6;
%"UNIVERSAL_GND"
"1","(-1875,-1100)","0","logical_power","I8";
;
HDL_POWER"AGND_HSC"
CDS_LIB"logical_power";
"A"1;
END.
